# T6G (Grand Teton) — schematic netlist excerpt (pin names and nets, part order shuffled) for the footprints in the layout excerpt that follows; sources: Cadence DE-HDL packaged netlist, KiCad conversion of 04192023_DAF0TMB3IC0_F0TG_MB_C_brd_V02_OCP.brd

C2315  Q_CAP  22UF 4V 20% X6S  pkg C0402  page 73 : A = PVDDCR_CPU0_P1 ; B = GND
C2420  Q_CAP  22UF 4V 20% X6S  pkg C0402  page 74 : A = PVDDCR_SOC_P1 ; B = GND

(kicad_pcb
	(version 20260206)
	(generator "pcbnew")
	(generator_version "10.0")
	(general
		(thickness 1.6)
		(legacy_teardrops no)
	)
	(paper "A4")
	(title_block
		(title "04192023_DAF0TMB3IC0_F0TG_MB_C_brd_V02_OCP.brd")
		(comment 1 "Grand Teton / footprints 8339-8340 of 8354")
	)
	(layers
		(0 "F.Cu" signal "TOP")
		(4 "In1.Cu" signal "GND")
		(6 "In2.Cu" signal "IN1")
		(8 "In3.Cu" signal "GND1")
		(10 "In4.Cu" signal "IN2")
		(12 "In5.Cu" signal "GND2")
		(14 "In6.Cu" signal "IN3")
		(16 "In7.Cu" signal "GND3")
		(18 "In8.Cu" signal "VCC")
		(20 "In9.Cu" signal "VCC1")
		(22 "In10.Cu" signal "GND4")
		(24 "In11.Cu" signal "IN4")
		(26 "In12.Cu" signal "GND5")
		(28 "In13.Cu" signal "IN5")
		(30 "In14.Cu" signal "GND6")
		(32 "In15.Cu" signal "IN6")
		(34 "In16.Cu" signal "GND7")
		(2 "B.Cu" signal "BOTTOM")
		(9 "F.Adhes" user "F.Adhesive")
		(11 "B.Adhes" user "B.Adhesive")
		(13 "F.Paste" user "Package Geometry/Pastemask Top")
		(15 "B.Paste" user "Package Geometry/Pastemask Bottom")
		(5 "F.SilkS" user "Ref Des/Silkscreen Top")
		(7 "B.SilkS" user "Ref Des/Silkscreen Bottom")
		(1 "F.Mask" user "Board Geometry/Soldermask Top")
		(3 "B.Mask" user "Board Geometry/Soldermask Bottom")
		(17 "Dwgs.User" user "User.Drawings")
		(19 "Cmts.User" user "User.Comments")
		(21 "Eco1.User" user "User.Eco1")
		(23 "Eco2.User" user "User.Eco2")
		(25 "Edge.Cuts" user "Board Geometry/Outline")
		(27 "Margin" user)
		(31 "F.CrtYd" user "Package Geometry/Place Bound Top")
		(29 "B.CrtYd" user "Package Geometry/Place Bound Bottom")
		(35 "F.Fab" user "Ref Des/Assembly Top")
		(33 "B.Fab" user "Ref Des/Assembly Bottom")
	)
	(footprint ""
		(layer "B.Cu")
		(at 122.10669 -248.479564)
		(property "Reference" "C2315"
			(at 0 0 0)
			(layer "B.SilkS")
			(hide yes)
			(effects
				(font
					(size 1.27 1.27)
				)
				(justify mirror)
			)
		)
		(property "Value" ""
			(at 0 0 0)
			(layer "B.Fab")
			(effects
				(font
					(size 1.27 1.27)
				)
				(justify mirror)
			)
		)
		(duplicate_pad_numbers_are_jumpers no)
		(fp_line
			(start -0.7874 -0.4064)
			(end -0.7874 0.4064)
			(stroke
				(width 0.1524)
				(type default)
			)
			(layer "B.SilkS")
		)
		(fp_line
			(start -0.7874 0.4064)
			(end 0.7874 0.4064)
			(stroke
				(width 0.1524)
				(type default)
			)
			(layer "B.SilkS")
		)
		(fp_line
			(start 0.7874 -0.4064)
			(end -0.7874 -0.4064)
			(stroke
				(width 0.1524)
				(type default)
			)
			(layer "B.SilkS")
		)
		(fp_line
			(start 0.7874 0.4064)
			(end 0.7874 -0.4064)
			(stroke
				(width 0.1524)
				(type default)
			)
			(layer "B.SilkS")
		)
		(fp_line
			(start -0.67945 -0.3048)
			(end -0.67945 0.3048)
			(stroke
				(width 0.1)
				(type default)
			)
			(layer "B.Fab")
		)
		(fp_line
			(start -0.67945 0.3048)
			(end -0.120396 0.3048)
			(stroke
				(width 0.1)
				(type default)
			)
			(layer "B.Fab")
		)
		(fp_line
			(start -0.12065 -0.3048)
			(end -0.67945 -0.3048)
			(stroke
				(width 0.1)
				(type default)
			)
			(layer "B.Fab")
		)
		(fp_line
			(start -0.12065 -0.2794)
			(end -0.12065 -0.3048)
			(stroke
				(width 0.1)
				(type default)
			)
			(layer "B.Fab")
		)
		(fp_line
			(start -0.120396 0.2794)
			(end 0.12065 0.2794)
			(stroke
				(width 0.1)
				(type default)
			)
			(layer "B.Fab")
		)
		(fp_line
			(start -0.120396 0.3048)
			(end -0.120396 0.2794)
			(stroke
				(width 0.1)
				(type default)
			)
			(layer "B.Fab")
		)
		(fp_line
			(start 0.12065 -0.305054)
			(end 0.12065 -0.2794)
			(stroke
				(width 0.1)
				(type default)
			)
			(layer "B.Fab")
		)
		(fp_line
			(start 0.12065 -0.2794)
			(end -0.12065 -0.2794)
			(stroke
				(width 0.1)
				(type default)
			)
			(layer "B.Fab")
		)
		(fp_line
			(start 0.12065 0.2794)
			(end 0.12065 0.3048)
			(stroke
				(width 0.1)
				(type default)
			)
			(layer "B.Fab")
		)
		(fp_line
			(start 0.12065 0.3048)
			(end 0.67945 0.3048)
			(stroke
				(width 0.1)
				(type default)
			)
			(layer "B.Fab")
		)
		(fp_line
			(start 0.67945 -0.305054)
			(end 0.12065 -0.305054)
			(stroke
				(width 0.1)
				(type default)
			)
			(layer "B.Fab")
		)
		(fp_line
			(start 0.67945 0.3048)
			(end 0.67945 -0.305054)
			(stroke
				(width 0.1)
				(type default)
			)
			(layer "B.Fab")
		)
		(pad "1" smd circle
			(at 0.40005 0 180)
			(size 0 0)
			(layers "B.Cu" "B.Mask" "B.Paste")
			(net "PVDDCR_CPU0_P1")
		)
		(pad "2" smd circle
			(at -0.40005 0 180)
			(size 0 0)
			(layers "B.Cu" "B.Mask" "B.Paste")
			(net "GND")
		)
	)
	(footprint ""
		(layer "B.Cu")
		(at 117.895624 -259.355336)
		(property "Reference" "C2420"
			(at 0 0 0)
			(layer "B.SilkS")
			(hide yes)
			(effects
				(font
					(size 1.27 1.27)
				)
				(justify mirror)
			)
		)
		(property "Value" ""
			(at 0 0 0)
			(layer "B.Fab")
			(effects
				(font
					(size 1.27 1.27)
				)
				(justify mirror)
			)
		)
		(duplicate_pad_numbers_are_jumpers no)
		(fp_line
			(start -0.7874 -0.4064)
			(end -0.7874 0.4064)
			(stroke
				(width 0.1524)
				(type default)
			)
			(layer "B.SilkS")
		)
		(fp_line
			(start -0.7874 0.4064)
			(end 0.7874 0.4064)
			(stroke
				(width 0.1524)
				(type default)
			)
			(layer "B.SilkS")
		)
		(fp_line
			(start 0.7874 -0.4064)
			(end -0.7874 -0.4064)
			(stroke
				(width 0.1524)
				(type default)
			)
			(layer "B.SilkS")
		)
		(fp_line
			(start 0.7874 0.4064)
			(end 0.7874 -0.4064)
			(stroke
				(width 0.1524)
				(type default)
			)
			(layer "B.SilkS")
		)
		(fp_line
			(start -0.67945 -0.3048)
			(end -0.67945 0.3048)
			(stroke
				(width 0.1)
				(type default)
			)
			(layer "B.Fab")
		)
		(fp_line
			(start -0.67945 0.3048)
			(end -0.120396 0.3048)
			(stroke
				(width 0.1)
				(type default)
			)
			(layer "B.Fab")
		)
		(fp_line
			(start -0.12065 -0.3048)
			(end -0.67945 -0.3048)
			(stroke
				(width 0.1)
				(type default)
			)
			(layer "B.Fab")
		)
		(fp_line
			(start -0.12065 -0.2794)
			(end -0.12065 -0.3048)
			(stroke
				(width 0.1)
				(type default)
			)
			(layer "B.Fab")
		)
		(fp_line
			(start -0.120396 0.2794)
			(end 0.12065 0.2794)
			(stroke
				(width 0.1)
				(type default)
			)
			(layer "B.Fab")
		)
		(fp_line
			(start -0.120396 0.3048)
			(end -0.120396 0.2794)
			(stroke
				(width 0.1)
				(type default)
			)
			(layer "B.Fab")
		)
		(fp_line
			(start 0.12065 -0.305054)
			(end 0.12065 -0.2794)
			(stroke
				(width 0.1)
				(type default)
			)
			(layer "B.Fab")
		)
		(fp_line
			(start 0.12065 -0.2794)
			(end -0.12065 -0.2794)
			(stroke
				(width 0.1)
				(type default)
			)
			(layer "B.Fab")
		)
		(fp_line
			(start 0.12065 0.2794)
			(end 0.12065 0.3048)
			(stroke
				(width 0.1)
				(type default)
			)
			(layer "B.Fab")
		)
		(fp_line
			(start 0.12065 0.3048)
			(end 0.67945 0.3048)
			(stroke
				(width 0.1)
				(type default)
			)
			(layer "B.Fab")
		)
		(fp_line
			(start 0.67945 -0.305054)
			(end 0.12065 -0.305054)
			(stroke
				(width 0.1)
				(type default)
			)
			(layer "B.Fab")
		)
		(fp_line
			(start 0.67945 0.3048)
			(end 0.67945 -0.305054)
			(stroke
				(width 0.1)
				(type default)
			)
			(layer "B.Fab")
		)
		(pad "1" smd circle
			(at 0.40005 0 180)
			(size 0 0)
			(layers "B.Cu" "B.Mask" "B.Paste")
			(net "PVDDCR_SOC_P1")
		)
		(pad "2" smd circle
			(at -0.40005 0 180)
			(size 0 0)
			(layers "B.Cu" "B.Mask" "B.Paste")
			(net "GND")
		)
	)
)
